(kicad_pcb
	(version 20260206)
	(generator "pcbnew")
	(generator_version "10.0")
	(general
		(thickness 1.6)
		(legacy_teardrops no)
	)
	(paper "A4")
	(title_block
		(title "03242023_DA0F0TMBIJ0_F0T_Motherboard_J_brd_V01_OCP.brd")
		(comment 1 "Grand Teton / footprints 267-273 of 6105")
	)
	(layers
		(0 "F.Cu" signal "TOP")
		(4 "In1.Cu" signal "GND")
		(6 "In2.Cu" signal "IN1")
		(8 "In3.Cu" signal "GND1")
		(10 "In4.Cu" signal "IN2")
		(12 "In5.Cu" signal "GND2")
		(14 "In6.Cu" signal "IN3")
		(16 "In7.Cu" signal "GND3")
		(18 "In8.Cu" signal "VCC")
		(20 "In9.Cu" signal "VCC1")
		(22 "In10.Cu" signal "GND4")
		(24 "In11.Cu" signal "IN4")
		(26 "In12.Cu" signal "GND5")
		(28 "In13.Cu" signal "IN5")
		(30 "In14.Cu" signal "GND6")
		(32 "In15.Cu" signal "IN6")
		(34 "In16.Cu" signal "GND7")
		(2 "B.Cu" signal "BOTTOM")
		(9 "F.Adhes" user "F.Adhesive")
		(11 "B.Adhes" user "B.Adhesive")
		(13 "F.Paste" user "Package Geometry/Pastemask Top")
		(15 "B.Paste" user "Package Geometry/Pastemask Bottom")
		(5 "F.SilkS" user "Ref Des/Silkscreen Top")
		(7 "B.SilkS" user "Ref Des/Silkscreen Bottom")
		(1 "F.Mask" user "Board Geometry/Soldermask Top")
		(3 "B.Mask" user "Board Geometry/Soldermask Bottom")
		(17 "Dwgs.User" user "User.Drawings")
		(19 "Cmts.User" user "User.Comments")
		(21 "Eco1.User" user "User.Eco1")
		(23 "Eco2.User" user "User.Eco2")
		(25 "Edge.Cuts" user "Board Geometry/Outline")
		(27 "Margin" user)
		(31 "F.CrtYd" user "Package Geometry/Place Bound Top")
		(29 "B.CrtYd" user "Package Geometry/Place Bound Bottom")
		(35 "F.Fab" user "Ref Des/Assembly Top")
		(33 "B.Fab" user "Ref Des/Assembly Bottom")
	)
	(footprint ""
		(layer "F.Cu")
		(at 441.050172 -32.173418 90)
		(property "Reference" "PC2155"
			(at 0 0 90)
			(layer "F.SilkS")
			(hide yes)
			(effects
				(font
					(size 1.27 1.27)
				)
			)
		)
		(property "Value" ""
			(at 0 0 90)
			(layer "F.Fab")
			(effects
				(font
					(size 1.27 1.27)
				)
			)
		)
		(duplicate_pad_numbers_are_jumpers no)
		(fp_line
			(start 0.7874 -0.4064)
			(end 0.7874 0.4064)
			(stroke
				(width 0.1524)
				(type default)
			)
			(layer "F.SilkS")
		)
		(fp_line
			(start -0.7874 -0.4064)
			(end 0.7874 -0.4064)
			(stroke
				(width 0.1524)
				(type default)
			)
			(layer "F.SilkS")
		)
		(fp_line
			(start 0.7874 0.4064)
			(end -0.7874 0.4064)
			(stroke
				(width 0.1524)
				(type default)
			)
			(layer "F.SilkS")
		)
		(fp_line
			(start -0.7874 0.4064)
			(end -0.7874 -0.4064)
			(stroke
				(width 0.1524)
				(type default)
			)
			(layer "F.SilkS")
		)
		(fp_line
			(start -0.12065 -0.305054)
			(end -0.12065 -0.2794)
			(stroke
				(width 0.1)
				(type default)
			)
			(layer "F.Fab")
		)
		(fp_line
			(start -0.67945 -0.305054)
			(end -0.12065 -0.305054)
			(stroke
				(width 0.1)
				(type default)
			)
			(layer "F.Fab")
		)
		(fp_line
			(start 0.67945 -0.3048)
			(end 0.67945 0.3048)
			(stroke
				(width 0.1)
				(type default)
			)
			(layer "F.Fab")
		)
		(fp_line
			(start 0.12065 -0.3048)
			(end 0.67945 -0.3048)
			(stroke
				(width 0.1)
				(type default)
			)
			(layer "F.Fab")
		)
		(fp_line
			(start 0.12065 -0.2794)
			(end 0.12065 -0.3048)
			(stroke
				(width 0.1)
				(type default)
			)
			(layer "F.Fab")
		)
		(fp_line
			(start -0.12065 -0.2794)
			(end 0.12065 -0.2794)
			(stroke
				(width 0.1)
				(type default)
			)
			(layer "F.Fab")
		)
		(fp_line
			(start 0.120396 0.2794)
			(end -0.12065 0.2794)
			(stroke
				(width 0.1)
				(type default)
			)
			(layer "F.Fab")
		)
		(fp_line
			(start -0.12065 0.2794)
			(end -0.12065 0.3048)
			(stroke
				(width 0.1)
				(type default)
			)
			(layer "F.Fab")
		)
		(fp_line
			(start 0.67945 0.3048)
			(end 0.120396 0.3048)
			(stroke
				(width 0.1)
				(type default)
			)
			(layer "F.Fab")
		)
		(fp_line
			(start 0.120396 0.3048)
			(end 0.120396 0.2794)
			(stroke
				(width 0.1)
				(type default)
			)
			(layer "F.Fab")
		)
		(fp_line
			(start -0.12065 0.3048)
			(end -0.67945 0.3048)
			(stroke
				(width 0.1)
				(type default)
			)
			(layer "F.Fab")
		)
		(fp_line
			(start -0.67945 0.3048)
			(end -0.67945 -0.305054)
			(stroke
				(width 0.1)
				(type default)
			)
			(layer "F.Fab")
		)
		(pad "1" smd circle
			(at -0.40005 0 90)
			(size 0 0)
			(layers "F.Cu" "F.Mask" "F.Paste")
			(net "P12V_OCP_SS_1")
		)
		(pad "2" smd circle
			(at 0.40005 0 90)
			(size 0 0)
			(layers "F.Cu" "F.Mask" "F.Paste")
			(net "GND")
		)
	)
	(footprint ""
		(layer "F.Cu")
		(at 113.494312 -128.392682 180)
		(property "Reference" "R3526"
			(at 0 0 180)
			(layer "F.SilkS")
			(hide yes)
			(effects
				(font
					(size 1.27 1.27)
				)
			)
		)
		(property "Value" ""
			(at 0 0 180)
			(layer "F.Fab")
			(effects
				(font
					(size 1.27 1.27)
				)
			)
		)
		(duplicate_pad_numbers_are_jumpers no)
		(fp_line
			(start 0.7874 0.4064)
			(end -0.7874 0.4064)
			(stroke
				(width 0.1524)
				(type default)
			)
			(layer "F.SilkS")
		)
		(fp_line
			(start 0.7874 -0.4064)
			(end 0.7874 0.4064)
			(stroke
				(width 0.1524)
				(type default)
			)
			(layer "F.SilkS")
		)
		(fp_line
			(start -0.7874 0.4064)
			(end -0.7874 -0.4064)
			(stroke
				(width 0.1524)
				(type default)
			)
			(layer "F.SilkS")
		)
		(fp_line
			(start -0.7874 -0.4064)
			(end 0.7874 -0.4064)
			(stroke
				(width 0.1524)
				(type default)
			)
			(layer "F.SilkS")
		)
		(fp_line
			(start 0.67945 0.3048)
			(end 0.120396 0.3048)
			(stroke
				(width 0.1)
				(type default)
			)
			(layer "F.Fab")
		)
		(fp_line
			(start 0.67945 -0.3048)
			(end 0.67945 0.3048)
			(stroke
				(width 0.1)
				(type default)
			)
			(layer "F.Fab")
		)
		(fp_line
			(start 0.12065 -0.2794)
			(end 0.12065 -0.3048)
			(stroke
				(width 0.1)
				(type default)
			)
			(layer "F.Fab")
		)
		(fp_line
			(start 0.12065 -0.3048)
			(end 0.67945 -0.3048)
			(stroke
				(width 0.1)
				(type default)
			)
			(layer "F.Fab")
		)
		(fp_line
			(start 0.120396 0.3048)
			(end 0.120396 0.2794)
			(stroke
				(width 0.1)
				(type default)
			)
			(layer "F.Fab")
		)
		(fp_line
			(start 0.120396 0.2794)
			(end -0.12065 0.2794)
			(stroke
				(width 0.1)
				(type default)
			)
			(layer "F.Fab")
		)
		(fp_line
			(start -0.12065 0.3048)
			(end -0.67945 0.3048)
			(stroke
				(width 0.1)
				(type default)
			)
			(layer "F.Fab")
		)
		(fp_line
			(start -0.12065 0.2794)
			(end -0.12065 0.3048)
			(stroke
				(width 0.1)
				(type default)
			)
			(layer "F.Fab")
		)
		(fp_line
			(start -0.12065 -0.2794)
			(end 0.12065 -0.2794)
			(stroke
				(width 0.1)
				(type default)
			)
			(layer "F.Fab")
		)
		(fp_line
			(start -0.12065 -0.305054)
			(end -0.12065 -0.2794)
			(stroke
				(width 0.1)
				(type default)
			)
			(layer "F.Fab")
		)
		(fp_line
			(start -0.67945 0.3048)
			(end -0.67945 -0.305054)
			(stroke
				(width 0.1)
				(type default)
			)
			(layer "F.Fab")
		)
		(fp_line
			(start -0.67945 -0.305054)
			(end -0.12065 -0.305054)
			(stroke
				(width 0.1)
				(type default)
			)
			(layer "F.Fab")
		)
		(pad "1" smd circle
			(at -0.40005 0 180)
			(size 0 0)
			(layers "F.Cu" "F.Mask" "F.Paste")
			(net "SMB_PCIE0_3V3AUX_SCL_R5")
		)
		(pad "2" smd circle
			(at 0.40005 0 180)
			(size 0 0)
			(layers "F.Cu" "F.Mask" "F.Paste")
			(net "SMB_SENSOR_E1S_3V3AUX_SCL")
		)
	)
	(footprint ""
		(layer "F.Cu")
		(at 426.607986 -366.691164 90)
		(property "Reference" "PR1782"
			(at 0 0 90)
			(layer "F.SilkS")
			(hide yes)
			(effects
				(font
					(size 1.27 1.27)
				)
			)
		)
		(property "Value" ""
			(at 0 0 90)
			(layer "F.Fab")
			(effects
				(font
					(size 1.27 1.27)
				)
			)
		)
		(duplicate_pad_numbers_are_jumpers no)
		(fp_line
			(start 0.7874 -0.4064)
			(end 0.7874 0.4064)
			(stroke
				(width 0.1524)
				(type default)
			)
			(layer "F.SilkS")
		)
		(fp_line
			(start -0.7874 -0.4064)
			(end 0.7874 -0.4064)
			(stroke
				(width 0.1524)
				(type default)
			)
			(layer "F.SilkS")
		)
		(fp_line
			(start 0.7874 0.4064)
			(end -0.7874 0.4064)
			(stroke
				(width 0.1524)
				(type default)
			)
			(layer "F.SilkS")
		)
		(fp_line
			(start -0.7874 0.4064)
			(end -0.7874 -0.4064)
			(stroke
				(width 0.1524)
				(type default)
			)
			(layer "F.SilkS")
		)
		(fp_line
			(start -0.12065 -0.305054)
			(end -0.12065 -0.2794)
			(stroke
				(width 0.1)
				(type default)
			)
			(layer "F.Fab")
		)
		(fp_line
			(start -0.67945 -0.305054)
			(end -0.12065 -0.305054)
			(stroke
				(width 0.1)
				(type default)
			)
			(layer "F.Fab")
		)
		(fp_line
			(start 0.67945 -0.3048)
			(end 0.67945 0.3048)
			(stroke
				(width 0.1)
				(type default)
			)
			(layer "F.Fab")
		)
		(fp_line
			(start 0.12065 -0.3048)
			(end 0.67945 -0.3048)
			(stroke
				(width 0.1)
				(type default)
			)
			(layer "F.Fab")
		)
		(fp_line
			(start 0.12065 -0.2794)
			(end 0.12065 -0.3048)
			(stroke
				(width 0.1)
				(type default)
			)
			(layer "F.Fab")
		)
		(fp_line
			(start -0.12065 -0.2794)
			(end 0.12065 -0.2794)
			(stroke
				(width 0.1)
				(type default)
			)
			(layer "F.Fab")
		)
		(fp_line
			(start 0.120396 0.2794)
			(end -0.12065 0.2794)
			(stroke
				(width 0.1)
				(type default)
			)
			(layer "F.Fab")
		)
		(fp_line
			(start -0.12065 0.2794)
			(end -0.12065 0.3048)
			(stroke
				(width 0.1)
				(type default)
			)
			(layer "F.Fab")
		)
		(fp_line
			(start 0.67945 0.3048)
			(end 0.120396 0.3048)
			(stroke
				(width 0.1)
				(type default)
			)
			(layer "F.Fab")
		)
		(fp_line
			(start 0.120396 0.3048)
			(end 0.120396 0.2794)
			(stroke
				(width 0.1)
				(type default)
			)
			(layer "F.Fab")
		)
		(fp_line
			(start -0.12065 0.3048)
			(end -0.67945 0.3048)
			(stroke
				(width 0.1)
				(type default)
			)
			(layer "F.Fab")
		)
		(fp_line
			(start -0.67945 0.3048)
			(end -0.67945 -0.305054)
			(stroke
				(width 0.1)
				(type default)
			)
			(layer "F.Fab")
		)
		(pad "1" smd circle
			(at -0.40005 0 90)
			(size 0 0)
			(layers "F.Cu" "F.Mask" "F.Paste")
			(net "SW_PVCCFA_EHV_FIVRA_CPU0_BOOT3")
		)
		(pad "2" smd circle
			(at 0.40005 0 90)
			(size 0 0)
			(layers "F.Cu" "F.Mask" "F.Paste")
			(net "SW_PVCCFA_EHV_FIVRA_CPU0_BOOT3_")
		)
	)
	(footprint ""
		(layer "F.Cu")
		(at 391.36828 -121.15546)
		(property "Reference" "ME13"
			(at -9.652 -9.540748 0)
			(unlocked yes)
			(layer "F.SilkS")
			(effects
				(font
					(size 0.7874 0.5842)
					(thickness 0.1524)
				)
				(justify left)
			)
		)
		(property "Value" ""
			(at 0 0 0)
			(layer "F.Fab")
			(effects
				(font
					(size 1.27 1.27)
				)
			)
		)
		(duplicate_pad_numbers_are_jumpers no)
		(zone
			(layer "F.Cu")
			(hatch none 0.5)
			(connect_pads
				(clearance 0)
			)
			(min_thickness 0.25)
			(keepout
				(tracks allowed)
				(vias allowed)
				(pads allowed)
				(copperpour allowed)
				(footprints not_allowed)
			)
			(placement
				(enabled no)
				(sheetname "")
			)
			(fill
				(thermal_gap 0.5)
				(thermal_bridge_width 0.5)
				(island_removal_mode 0)
			)
			(polygon
				(pts
					(arc
						(start 401.36826 -121.15546)
						(mid 381.3683 -121.15546)
						(end 401.36826 -121.15546)
					)
				)
			)
		)
	)
	(footprint ""
		(layer "F.Cu")
		(at 249.52579 -53.424582 -90)
		(property "Reference" "PR3957"
			(at 0 0 270)
			(layer "F.SilkS")
			(hide yes)
			(effects
				(font
					(size 1.27 1.27)
				)
			)
		)
		(property "Value" ""
			(at 0 0 270)
			(layer "F.Fab")
			(effects
				(font
					(size 1.27 1.27)
				)
			)
		)
		(duplicate_pad_numbers_are_jumpers no)
		(fp_line
			(start -1.2954 0.5842)
			(end -1.2954 -0.5842)
			(stroke
				(width 0.1524)
				(type default)
			)
			(layer "F.SilkS")
		)
		(fp_line
			(start 1.2954 0.5842)
			(end -1.2954 0.5842)
			(stroke
				(width 0.1524)
				(type default)
			)
			(layer "F.SilkS")
		)
		(fp_line
			(start -1.2954 -0.5842)
			(end 1.2954 -0.5842)
			(stroke
				(width 0.1524)
				(type default)
			)
			(layer "F.SilkS")
		)
		(fp_line
			(start 1.2954 -0.5842)
			(end 1.2954 0.5842)
			(stroke
				(width 0.1524)
				(type default)
			)
			(layer "F.SilkS")
		)
		(fp_line
			(start -0.8636 0.4572)
			(end -0.8636 0.4318)
			(stroke
				(width 0.1)
				(type default)
			)
			(layer "F.Fab")
		)
		(fp_line
			(start 0.8636 0.4572)
			(end -0.8636 0.4572)
			(stroke
				(width 0.1)
				(type default)
			)
			(layer "F.Fab")
		)
		(fp_line
			(start -0.8636 0.4318)
			(end -0.8636 0.4064)
			(stroke
				(width 0.1)
				(type default)
			)
			(layer "F.Fab")
		)
		(fp_line
			(start -1.1938 0.4064)
			(end -1.1938 -0.406654)
			(stroke
				(width 0.1)
				(type default)
			)
			(layer "F.Fab")
		)
		(fp_line
			(start -0.8636 0.4064)
			(end -1.1938 0.4064)
			(stroke
				(width 0.1)
				(type default)
			)
			(layer "F.Fab")
		)
		(fp_line
			(start 0.8636 0.4064)
			(end 0.8636 0.4572)
			(stroke
				(width 0.1)
				(type default)
			)
			(layer "F.Fab")
		)
		(fp_line
			(start 1.1938 0.4064)
			(end 0.8636 0.4064)
			(stroke
				(width 0.1)
				(type default)
			)
			(layer "F.Fab")
		)
		(fp_line
			(start -1.1938 -0.406654)
			(end -0.8636 -0.406654)
			(stroke
				(width 0.1)
				(type default)
			)
			(layer "F.Fab")
		)
		(fp_line
			(start -0.8636 -0.406654)
			(end -0.8636 -0.4572)
			(stroke
				(width 0.1)
				(type default)
			)
			(layer "F.Fab")
		)
		(fp_line
			(start 0.8636 -0.406654)
			(end 1.1938 -0.406654)
			(stroke
				(width 0.1)
				(type default)
			)
			(layer "F.Fab")
		)
		(fp_line
			(start 1.1938 -0.406654)
			(end 1.1938 0.4064)
			(stroke
				(width 0.1)
				(type default)
			)
			(layer "F.Fab")
		)
		(fp_line
			(start -0.8636 -0.4572)
			(end 0.8636 -0.4572)
			(stroke
				(width 0.1)
				(type default)
			)
			(layer "F.Fab")
		)
		(fp_line
			(start 0.8636 -0.4572)
			(end 0.8636 -0.406654)
			(stroke
				(width 0.1)
				(type default)
			)
			(layer "F.Fab")
		)
		(pad "1" smd rect
			(at -0.7366 0 180)
			(size 0.7112 0.8128)
			(layers "F.Cu" "F.Mask" "F.Paste")
			(net "P12V_AUX")
		)
		(pad "2" smd rect
			(at 0.7366 0 180)
			(size 0.7112 0.8128)
			(layers "F.Cu" "F.Mask" "F.Paste")
			(net "P12V_E1S_AVIN_PD_0")
		)
	)
	(footprint ""
		(layer "F.Cu")
		(at 455.617834 -93.437964)
		(property "Reference" "R3231"
			(at 0 0 0)
			(layer "F.SilkS")
			(hide yes)
			(effects
				(font
					(size 1.27 1.27)
				)
			)
		)
		(property "Value" ""
			(at 0 0 0)
			(layer "F.Fab")
			(effects
				(font
					(size 1.27 1.27)
				)
			)
		)
		(duplicate_pad_numbers_are_jumpers no)
		(fp_line
			(start -0.7874 -0.4064)
			(end 0.7874 -0.4064)
			(stroke
				(width 0.1524)
				(type default)
			)
			(layer "F.SilkS")
		)
		(fp_line
			(start -0.7874 0.4064)
			(end -0.7874 -0.4064)
			(stroke
				(width 0.1524)
				(type default)
			)
			(layer "F.SilkS")
		)
		(fp_line
			(start 0.7874 -0.4064)
			(end 0.7874 0.4064)
			(stroke
				(width 0.1524)
				(type default)
			)
			(layer "F.SilkS")
		)
		(fp_line
			(start 0.7874 0.4064)
			(end -0.7874 0.4064)
			(stroke
				(width 0.1524)
				(type default)
			)
			(layer "F.SilkS")
		)
		(fp_line
			(start -0.67945 -0.305054)
			(end -0.12065 -0.305054)
			(stroke
				(width 0.1)
				(type default)
			)
			(layer "F.Fab")
		)
		(fp_line
			(start -0.67945 0.3048)
			(end -0.67945 -0.305054)
			(stroke
				(width 0.1)
				(type default)
			)
			(layer "F.Fab")
		)
		(fp_line
			(start -0.12065 -0.305054)
			(end -0.12065 -0.2794)
			(stroke
				(width 0.1)
				(type default)
			)
			(layer "F.Fab")
		)
		(fp_line
			(start -0.12065 -0.2794)
			(end 0.12065 -0.2794)
			(stroke
				(width 0.1)
				(type default)
			)
			(layer "F.Fab")
		)
		(fp_line
			(start -0.12065 0.2794)
			(end -0.12065 0.3048)
			(stroke
				(width 0.1)
				(type default)
			)
			(layer "F.Fab")
		)
		(fp_line
			(start -0.12065 0.3048)
			(end -0.67945 0.3048)
			(stroke
				(width 0.1)
				(type default)
			)
			(layer "F.Fab")
		)
		(fp_line
			(start 0.120396 0.2794)
			(end -0.12065 0.2794)
			(stroke
				(width 0.1)
				(type default)
			)
			(layer "F.Fab")
		)
		(fp_line
			(start 0.120396 0.3048)
			(end 0.120396 0.2794)
			(stroke
				(width 0.1)
				(type default)
			)
			(layer "F.Fab")
		)
		(fp_line
			(start 0.12065 -0.3048)
			(end 0.67945 -0.3048)
			(stroke
				(width 0.1)
				(type default)
			)
			(layer "F.Fab")
		)
		(fp_line
			(start 0.12065 -0.2794)
			(end 0.12065 -0.3048)
			(stroke
				(width 0.1)
				(type default)
			)
			(layer "F.Fab")
		)
		(fp_line
			(start 0.67945 -0.3048)
			(end 0.67945 0.3048)
			(stroke
				(width 0.1)
				(type default)
			)
			(layer "F.Fab")
		)
		(fp_line
			(start 0.67945 0.3048)
			(end 0.120396 0.3048)
			(stroke
				(width 0.1)
				(type default)
			)
			(layer "F.Fab")
		)
		(pad "1" smd circle
			(at -0.40005 0)
			(size 0 0)
			(layers "F.Cu" "F.Mask" "F.Paste")
			(net "OCP_SFF_AUX_PWR_EN")
		)
		(pad "2" smd circle
			(at 0.40005 0)
			(size 0 0)
			(layers "F.Cu" "F.Mask" "F.Paste")
			(net "OCP_SFF_AUX_PWR_EN_R4")
		)
	)
	(footprint ""
		(layer "F.Cu")
		(at 151.82977 -40.50792 180)
		(property "Reference" "R4463"
			(at 0 0 180)
			(layer "F.SilkS")
			(hide yes)
			(effects
				(font
					(size 1.27 1.27)
				)
			)
		)
		(property "Value" ""
			(at 0 0 180)
			(layer "F.Fab")
			(effects
				(font
					(size 1.27 1.27)
				)
			)
		)
		(duplicate_pad_numbers_are_jumpers no)
		(fp_line
			(start 0.7874 0.4064)
			(end -0.7874 0.4064)
			(stroke
				(width 0.1524)
				(type default)
			)
			(layer "F.SilkS")
		)
		(fp_line
			(start 0.7874 -0.4064)
			(end 0.7874 0.4064)
			(stroke
				(width 0.1524)
				(type default)
			)
			(layer "F.SilkS")
		)
		(fp_line
			(start -0.7874 0.4064)
			(end -0.7874 -0.4064)
			(stroke
				(width 0.1524)
				(type default)
			)
			(layer "F.SilkS")
		)
		(fp_line
			(start -0.7874 -0.4064)
			(end 0.7874 -0.4064)
			(stroke
				(width 0.1524)
				(type default)
			)
			(layer "F.SilkS")
		)
		(fp_line
			(start 0.67945 0.3048)
			(end 0.120396 0.3048)
			(stroke
				(width 0.1)
				(type default)
			)
			(layer "F.Fab")
		)
		(fp_line
			(start 0.67945 -0.3048)
			(end 0.67945 0.3048)
			(stroke
				(width 0.1)
				(type default)
			)
			(layer "F.Fab")
		)
		(fp_line
			(start 0.12065 -0.2794)
			(end 0.12065 -0.3048)
			(stroke
				(width 0.1)
				(type default)
			)
			(layer "F.Fab")
		)
		(fp_line
			(start 0.12065 -0.3048)
			(end 0.67945 -0.3048)
			(stroke
				(width 0.1)
				(type default)
			)
			(layer "F.Fab")
		)
		(fp_line
			(start 0.120396 0.3048)
			(end 0.120396 0.2794)
			(stroke
				(width 0.1)
				(type default)
			)
			(layer "F.Fab")
		)
		(fp_line
			(start 0.120396 0.2794)
			(end -0.12065 0.2794)
			(stroke
				(width 0.1)
				(type default)
			)
			(layer "F.Fab")
		)
		(fp_line
			(start -0.12065 0.3048)
			(end -0.67945 0.3048)
			(stroke
				(width 0.1)
				(type default)
			)
			(layer "F.Fab")
		)
		(fp_line
			(start -0.12065 0.2794)
			(end -0.12065 0.3048)
			(stroke
				(width 0.1)
				(type default)
			)
			(layer "F.Fab")
		)
		(fp_line
			(start -0.12065 -0.2794)
			(end 0.12065 -0.2794)
			(stroke
				(width 0.1)
				(type default)
			)
			(layer "F.Fab")
		)
		(fp_line
			(start -0.12065 -0.305054)
			(end -0.12065 -0.2794)
			(stroke
				(width 0.1)
				(type default)
			)
			(layer "F.Fab")
		)
		(fp_line
			(start -0.67945 0.3048)
			(end -0.67945 -0.305054)
			(stroke
				(width 0.1)
				(type default)
			)
			(layer "F.Fab")
		)
		(fp_line
			(start -0.67945 -0.305054)
			(end -0.12065 -0.305054)
			(stroke
				(width 0.1)
				(type default)
			)
			(layer "F.Fab")
		)
		(pad "1" smd circle
			(at -0.40005 0 180)
			(size 0 0)
			(layers "F.Cu" "F.Mask" "F.Paste")
			(net "USB_HUB_2_RREF")
		)
		(pad "2" smd circle
			(at 0.40005 0 180)
			(size 0 0)
			(layers "F.Cu" "F.Mask" "F.Paste")
			(net "GND")
		)
	)
)
